(kicad_pcb
	(version 20221018)
	(generator pcbnew)
	(general
    (thickness 1.7403)
  )
	(paper "A4")
	(title_block
    (title "Data Center RDIMM DDR4 Tester")
    (date "2024-09-30")
    (rev "1.2.4")
		(comment 9 "footprints 439-447 of 690")
	)
	(layers
    (0 "F.Cu" signal)
    (1 "In1.Cu" power)
    (2 "In2.Cu" signal)
    (3 "In3.Cu" power)
    (4 "In4.Cu" power)
    (5 "In5.Cu" signal)
    (6 "In6.Cu" power)
    (7 "In7.Cu" signal)
    (8 "In8.Cu" power)
    (9 "In9.Cu" signal)
    (10 "In10.Cu" power)
    (31 "B.Cu" signal)
    (32 "B.Adhes" user "B.Adhesive")
    (33 "F.Adhes" user "F.Adhesive")
    (34 "B.Paste" user)
    (35 "F.Paste" user)
    (36 "B.SilkS" user "B.Silkscreen")
    (37 "F.SilkS" user "F.Silkscreen")
    (38 "B.Mask" user)
    (39 "F.Mask" user)
    (40 "Dwgs.User" user "User.Drawings")
    (41 "Cmts.User" user "User.Comments")
    (42 "Eco1.User" user "User.Eco1")
    (43 "Eco2.User" user "User.Eco2")
    (44 "Edge.Cuts" user)
    (45 "Margin" user)
    (46 "B.CrtYd" user "B.Courtyard")
    (47 "F.CrtYd" user "F.Courtyard")
    (48 "B.Fab" user)
    (49 "F.Fab" user)
  )
	(footprint "data-center-rdimm-ddr4-tester-footprints:C_0201" (layer "B.Cu")
    (at 189.186328 94.510008 180)
    (descr "Capacitor SMD 0201")
    (tags "capacitor SMD 0201")
    (property "Author" "Antmicro")
    (property "Dielectric" "")
    (property "License" "Apache-2.0")
    (property "MPN" "CC0201KRX6S5BB104")
    (property "Manufacturer" "Yaego")
    (property "Sheetfile" "fpga-power.kicad_sch")
    (property "Sheetname" "FPGA power")
    (property "Val" "100n")
    (property "Voltage" "")
    (property "ki_description" " ")
    (attr smd)
    (fp_text reference "C54" (at -1.083672 -1.199992) (layer "B.SilkS")
        (effects (font (size 0.7 0.7) (thickness 0.15)) (justify left bottom mirror))
    )
    (fp_text value "C_100n_0201" (at 0 -1.4) (layer "B.Fab") hide
        (effects (font (size 0.7 0.7) (thickness 0.15)) (justify left bottom mirror))
    )
    (fp_text user "${REFERENCE}" (at -0.72 -3.4) (layer "B.Fab") hide
        (effects (font (size 0.7 0.7) (thickness 0.15)) (justify left bottom mirror))
    )
    (fp_text user "Author: Antmicro" (at -0.72 -5.4) (layer "B.Fab") hide
        (effects (font (size 0.7 0.7) (thickness 0.15)) (justify left bottom mirror))
    )
    (fp_text user "License: Apache-2.0" (at -0.72 -4.4) (layer "B.Fab") hide
        (effects (font (size 0.7 0.7) (thickness 0.15)) (justify left bottom mirror))
    )
    (fp_rect (start -0.72 0.38) (end 0.72 -0.38)
      (stroke (width 0.05) (type solid)) (fill none) (layer "B.CrtYd"))
    (fp_rect (start 0.3 -0.15) (end -0.301 0.149)
      (stroke (width 0.15) (type solid)) (fill none) (layer "B.Fab"))
    (pad "" smd roundrect (at -0.349 0.002 180) (size 0.318 0.36) (layers "B.Paste") (roundrect_rratio 0.25))
    (pad "" smd roundrect (at 0.341 0.002 180) (size 0.318 0.36) (layers "B.Paste") (roundrect_rratio 0.25))
    (pad "1" smd roundrect (at -0.321 0.002 180) (size 0.46 0.4) (layers "B.Cu" "B.Mask") (roundrect_rratio 0.25)
      (net 147 "1V0_SYS") (pintype "passive"))
    (pad "2" smd roundrect (at 0.32 0.002 180) (size 0.46 0.4) (layers "B.Cu" "B.Mask") (roundrect_rratio 0.25)
      (net 9 "GND") (pintype "passive"))
  )
	(footprint "data-center-rdimm-ddr4-tester-footprints:C_0201" (layer "B.Cu")
    (at 181.2 86.610008 -90)
    (descr "Capacitor SMD 0201")
    (tags "capacitor SMD 0201")
    (property "Author" "Antmicro")
    (property "Dielectric" "")
    (property "License" "Apache-2.0")
    (property "MPN" "CC0201KRX6S5BB104")
    (property "Manufacturer" "Yaego")
    (property "Sheetfile" "fpga-power.kicad_sch")
    (property "Sheetname" "FPGA power")
    (property "Val" "100n")
    (property "Voltage" "")
    (property "ki_description" " ")
    (attr smd)
    (fp_text reference "C57" (at -10.350008 -18.06 90) (layer "B.SilkS")
        (effects (font (size 0.7 0.7) (thickness 0.15)) (justify left bottom mirror))
    )
    (fp_text value "C_100n_0201" (at 0 -1.4 90) (layer "B.Fab") hide
        (effects (font (size 0.7 0.7) (thickness 0.15)) (justify left bottom mirror))
    )
    (fp_text user "License: Apache-2.0" (at -0.72 -4.4 90) (layer "B.Fab") hide
        (effects (font (size 0.7 0.7) (thickness 0.15)) (justify left bottom mirror))
    )
    (fp_text user "Author: Antmicro" (at -0.72 -5.4 90) (layer "B.Fab") hide
        (effects (font (size 0.7 0.7) (thickness 0.15)) (justify left bottom mirror))
    )
    (fp_text user "${REFERENCE}" (at -0.72 -3.4 90) (layer "B.Fab") hide
        (effects (font (size 0.7 0.7) (thickness 0.15)) (justify left bottom mirror))
    )
    (fp_rect (start -0.72 0.38) (end 0.72 -0.38)
      (stroke (width 0.05) (type solid)) (fill none) (layer "B.CrtYd"))
    (fp_rect (start 0.3 -0.15) (end -0.301 0.149)
      (stroke (width 0.15) (type solid)) (fill none) (layer "B.Fab"))
    (pad "" smd roundrect (at -0.349 0.002 270) (size 0.318 0.36) (layers "B.Paste") (roundrect_rratio 0.25))
    (pad "" smd roundrect (at 0.341 0.002 270) (size 0.318 0.36) (layers "B.Paste") (roundrect_rratio 0.25))
    (pad "1" smd roundrect (at -0.321 0.002 270) (size 0.46 0.4) (layers "B.Cu" "B.Mask") (roundrect_rratio 0.25)
      (net 147 "1V0_SYS") (pintype "passive"))
    (pad "2" smd roundrect (at 0.32 0.002 270) (size 0.46 0.4) (layers "B.Cu" "B.Mask") (roundrect_rratio 0.25)
      (net 9 "GND") (pintype "passive"))
  )
	(footprint "data-center-rdimm-ddr4-tester-footprints:C_0201" (layer "B.Cu")
    (at 181.186328 88.560008 -90)
    (descr "Capacitor SMD 0201")
    (tags "capacitor SMD 0201")
    (property "Author" "Antmicro")
    (property "Dielectric" "")
    (property "License" "Apache-2.0")
    (property "MPN" "CC0201KRX6S5BB104")
    (property "Manufacturer" "Yaego")
    (property "Sheetfile" "fpga-power.kicad_sch")
    (property "Sheetname" "FPGA power")
    (property "Val" "100n")
    (property "Voltage" "")
    (property "ki_description" " ")
    (attr smd)
    (fp_text reference "C60" (at -10.300008 -18.093672 90) (layer "B.SilkS")
        (effects (font (size 0.7 0.7) (thickness 0.15)) (justify left bottom mirror))
    )
    (fp_text value "C_100n_0201" (at 0 -1.4 90) (layer "B.Fab") hide
        (effects (font (size 0.7 0.7) (thickness 0.15)) (justify left bottom mirror))
    )
    (fp_text user "${REFERENCE}" (at -0.72 -3.4 90) (layer "B.Fab") hide
        (effects (font (size 0.7 0.7) (thickness 0.15)) (justify left bottom mirror))
    )
    (fp_text user "License: Apache-2.0" (at -0.72 -4.4 90) (layer "B.Fab") hide
        (effects (font (size 0.7 0.7) (thickness 0.15)) (justify left bottom mirror))
    )
    (fp_text user "Author: Antmicro" (at -0.72 -5.4 90) (layer "B.Fab") hide
        (effects (font (size 0.7 0.7) (thickness 0.15)) (justify left bottom mirror))
    )
    (fp_rect (start -0.72 0.38) (end 0.72 -0.38)
      (stroke (width 0.05) (type solid)) (fill none) (layer "B.CrtYd"))
    (fp_rect (start 0.3 -0.15) (end -0.301 0.149)
      (stroke (width 0.15) (type solid)) (fill none) (layer "B.Fab"))
    (pad "" smd roundrect (at -0.349 0.002 270) (size 0.318 0.36) (layers "B.Paste") (roundrect_rratio 0.25))
    (pad "" smd roundrect (at 0.341 0.002 270) (size 0.318 0.36) (layers "B.Paste") (roundrect_rratio 0.25))
    (pad "1" smd roundrect (at -0.321 0.002 270) (size 0.46 0.4) (layers "B.Cu" "B.Mask") (roundrect_rratio 0.25)
      (net 147 "1V0_SYS") (pintype "passive"))
    (pad "2" smd roundrect (at 0.32 0.002 270) (size 0.46 0.4) (layers "B.Cu" "B.Mask") (roundrect_rratio 0.25)
      (net 9 "GND") (pintype "passive"))
  )
	(footprint "data-center-rdimm-ddr4-tester-footprints:C_0201" (layer "B.Cu")
    (at 182.186328 86.560008 90)
    (descr "Capacitor SMD 0201")
    (tags "capacitor SMD 0201")
    (property "Author" "Antmicro")
    (property "Dielectric" "")
    (property "License" "Apache-2.0")
    (property "MPN" "CC0201KRX6S5BB104")
    (property "Manufacturer" "Yaego")
    (property "Sheetfile" "fpga-power.kicad_sch")
    (property "Sheetname" "FPGA power")
    (property "Val" "100n")
    (property "Voltage" "")
    (property "ki_description" " ")
    (attr smd)
    (fp_text reference "C61" (at 10.300008 18.003672 270) (layer "B.SilkS")
        (effects (font (size 0.7 0.7) (thickness 0.15)) (justify left bottom mirror))
    )
    (fp_text value "C_100n_0201" (at 0 -1.4 270) (layer "B.Fab") hide
        (effects (font (size 0.7 0.7) (thickness 0.15)) (justify left bottom mirror))
    )
    (fp_text user "${REFERENCE}" (at -0.72 -3.4 270) (layer "B.Fab") hide
        (effects (font (size 0.7 0.7) (thickness 0.15)) (justify left bottom mirror))
    )
    (fp_text user "Author: Antmicro" (at -0.72 -5.4 270) (layer "B.Fab") hide
        (effects (font (size 0.7 0.7) (thickness 0.15)) (justify left bottom mirror))
    )
    (fp_text user "License: Apache-2.0" (at -0.72 -4.4 270) (layer "B.Fab") hide
        (effects (font (size 0.7 0.7) (thickness 0.15)) (justify left bottom mirror))
    )
    (fp_rect (start -0.72 0.38) (end 0.72 -0.38)
      (stroke (width 0.05) (type solid)) (fill none) (layer "B.CrtYd"))
    (fp_rect (start 0.3 -0.15) (end -0.301 0.149)
      (stroke (width 0.15) (type solid)) (fill none) (layer "B.Fab"))
    (pad "" smd roundrect (at -0.349 0.002 90) (size 0.318 0.36) (layers "B.Paste") (roundrect_rratio 0.25))
    (pad "" smd roundrect (at 0.341 0.002 90) (size 0.318 0.36) (layers "B.Paste") (roundrect_rratio 0.25))
    (pad "1" smd roundrect (at -0.321 0.002 90) (size 0.46 0.4) (layers "B.Cu" "B.Mask") (roundrect_rratio 0.25)
      (net 147 "1V0_SYS") (pintype "passive"))
    (pad "2" smd roundrect (at 0.32 0.002 90) (size 0.46 0.4) (layers "B.Cu" "B.Mask") (roundrect_rratio 0.25)
      (net 9 "GND") (pintype "passive"))
  )
	(footprint "data-center-rdimm-ddr4-tester-footprints:C_0201" (layer "B.Cu")
    (at 183.186328 88.560008 -90)
    (descr "Capacitor SMD 0201")
    (tags "capacitor SMD 0201")
    (property "Author" "Antmicro")
    (property "Dielectric" "")
    (property "License" "Apache-2.0")
    (property "MPN" "CC0201KRX6S5BB104")
    (property "Manufacturer" "Yaego")
    (property "Sheetfile" "fpga-power.kicad_sch")
    (property "Sheetname" "FPGA power")
    (property "Val" "100n")
    (property "Voltage" "")
    (property "ki_description" " ")
    (attr smd)
    (fp_text reference "C62" (at -10.270008 -18.053672 90) (layer "B.SilkS")
        (effects (font (size 0.7 0.7) (thickness 0.15)) (justify left bottom mirror))
    )
    (fp_text value "C_100n_0201" (at 0 -1.4 90) (layer "B.Fab") hide
        (effects (font (size 0.7 0.7) (thickness 0.15)) (justify left bottom mirror))
    )
    (fp_text user "Author: Antmicro" (at -0.72 -5.4 90) (layer "B.Fab") hide
        (effects (font (size 0.7 0.7) (thickness 0.15)) (justify left bottom mirror))
    )
    (fp_text user "${REFERENCE}" (at -0.72 -3.4 90) (layer "B.Fab") hide
        (effects (font (size 0.7 0.7) (thickness 0.15)) (justify left bottom mirror))
    )
    (fp_text user "License: Apache-2.0" (at -0.72 -4.4 90) (layer "B.Fab") hide
        (effects (font (size 0.7 0.7) (thickness 0.15)) (justify left bottom mirror))
    )
    (fp_rect (start -0.72 0.38) (end 0.72 -0.38)
      (stroke (width 0.05) (type solid)) (fill none) (layer "B.CrtYd"))
    (fp_rect (start 0.3 -0.15) (end -0.301 0.149)
      (stroke (width 0.15) (type solid)) (fill none) (layer "B.Fab"))
    (pad "" smd roundrect (at -0.349 0.002 270) (size 0.318 0.36) (layers "B.Paste") (roundrect_rratio 0.25))
    (pad "" smd roundrect (at 0.341 0.002 270) (size 0.318 0.36) (layers "B.Paste") (roundrect_rratio 0.25))
    (pad "1" smd roundrect (at -0.321 0.002 270) (size 0.46 0.4) (layers "B.Cu" "B.Mask") (roundrect_rratio 0.25)
      (net 147 "1V0_SYS") (pintype "passive"))
    (pad "2" smd roundrect (at 0.32 0.002 270) (size 0.46 0.4) (layers "B.Cu" "B.Mask") (roundrect_rratio 0.25)
      (net 9 "GND") (pintype "passive"))
  )
	(footprint "data-center-rdimm-ddr4-tester-footprints:C_0201" (layer "B.Cu")
    (at 183.186328 86.560008 -90)
    (descr "Capacitor SMD 0201")
    (tags "capacitor SMD 0201")
    (property "Author" "Antmicro")
    (property "Dielectric" "")
    (property "License" "Apache-2.0")
    (property "MPN" "CC0201KRX6S5BB104")
    (property "Manufacturer" "Yaego")
    (property "Sheetfile" "fpga-power.kicad_sch")
    (property "Sheetname" "FPGA power")
    (property "Val" "100n")
    (property "Voltage" "")
    (property "ki_description" " ")
    (attr smd)
    (fp_text reference "C63" (at -10.320008 -17.963672 90) (layer "B.SilkS")
        (effects (font (size 0.7 0.7) (thickness 0.15)) (justify left bottom mirror))
    )
    (fp_text value "C_100n_0201" (at 0 -1.4 90) (layer "B.Fab") hide
        (effects (font (size 0.7 0.7) (thickness 0.15)) (justify left bottom mirror))
    )
    (fp_text user "Author: Antmicro" (at -0.72 -5.4 90) (layer "B.Fab") hide
        (effects (font (size 0.7 0.7) (thickness 0.15)) (justify left bottom mirror))
    )
    (fp_text user "${REFERENCE}" (at -0.72 -3.4 90) (layer "B.Fab") hide
        (effects (font (size 0.7 0.7) (thickness 0.15)) (justify left bottom mirror))
    )
    (fp_text user "License: Apache-2.0" (at -0.72 -4.4 90) (layer "B.Fab") hide
        (effects (font (size 0.7 0.7) (thickness 0.15)) (justify left bottom mirror))
    )
    (fp_rect (start -0.72 0.38) (end 0.72 -0.38)
      (stroke (width 0.05) (type solid)) (fill none) (layer "B.CrtYd"))
    (fp_rect (start 0.3 -0.15) (end -0.301 0.149)
      (stroke (width 0.15) (type solid)) (fill none) (layer "B.Fab"))
    (pad "" smd roundrect (at -0.349 0.002 270) (size 0.318 0.36) (layers "B.Paste") (roundrect_rratio 0.25))
    (pad "" smd roundrect (at 0.341 0.002 270) (size 0.318 0.36) (layers "B.Paste") (roundrect_rratio 0.25))
    (pad "1" smd roundrect (at -0.321 0.002 270) (size 0.46 0.4) (layers "B.Cu" "B.Mask") (roundrect_rratio 0.25)
      (net 147 "1V0_SYS") (pintype "passive"))
    (pad "2" smd roundrect (at 0.32 0.002 270) (size 0.46 0.4) (layers "B.Cu" "B.Mask") (roundrect_rratio 0.25)
      (net 9 "GND") (pintype "passive"))
  )
	(footprint "data-center-rdimm-ddr4-tester-footprints:C_0201" (layer "B.Cu")
    (at 182.186328 91.560008 90)
    (descr "Capacitor SMD 0201")
    (tags "capacitor SMD 0201")
    (property "Author" "Antmicro")
    (property "Dielectric" "")
    (property "License" "Apache-2.0")
    (property "MPN" "CC0201KRX6S5BB104")
    (property "Manufacturer" "Yaego")
    (property "Sheetfile" "fpga-power.kicad_sch")
    (property "Sheetname" "FPGA power")
    (property "Val" "100n")
    (property "Voltage" "")
    (property "ki_description" " ")
    (attr smd)
    (fp_text reference "C65" (at 10.330008 18.403672 270) (layer "B.SilkS")
        (effects (font (size 0.7 0.7) (thickness 0.15)) (justify left bottom mirror))
    )
    (fp_text value "C_100n_0201" (at 0 -1.4 270) (layer "B.Fab") hide
        (effects (font (size 0.7 0.7) (thickness 0.15)) (justify left bottom mirror))
    )
    (fp_text user "${REFERENCE}" (at -0.72 -3.4 270) (layer "B.Fab") hide
        (effects (font (size 0.7 0.7) (thickness 0.15)) (justify left bottom mirror))
    )
    (fp_text user "License: Apache-2.0" (at -0.72 -4.4 270) (layer "B.Fab") hide
        (effects (font (size 0.7 0.7) (thickness 0.15)) (justify left bottom mirror))
    )
    (fp_text user "Author: Antmicro" (at -0.72 -5.4 270) (layer "B.Fab") hide
        (effects (font (size 0.7 0.7) (thickness 0.15)) (justify left bottom mirror))
    )
    (fp_rect (start -0.72 0.38) (end 0.72 -0.38)
      (stroke (width 0.05) (type solid)) (fill none) (layer "B.CrtYd"))
    (fp_rect (start 0.3 -0.15) (end -0.301 0.149)
      (stroke (width 0.15) (type solid)) (fill none) (layer "B.Fab"))
    (pad "" smd roundrect (at -0.349 0.002 90) (size 0.318 0.36) (layers "B.Paste") (roundrect_rratio 0.25))
    (pad "" smd roundrect (at 0.341 0.002 90) (size 0.318 0.36) (layers "B.Paste") (roundrect_rratio 0.25))
    (pad "1" smd roundrect (at -0.321 0.002 90) (size 0.46 0.4) (layers "B.Cu" "B.Mask") (roundrect_rratio 0.25)
      (net 147 "1V0_SYS") (pintype "passive"))
    (pad "2" smd roundrect (at 0.32 0.002 90) (size 0.46 0.4) (layers "B.Cu" "B.Mask") (roundrect_rratio 0.25)
      (net 9 "GND") (pintype "passive"))
  )
	(footprint "data-center-rdimm-ddr4-tester-footprints:C_0201" (layer "B.Cu")
    (at 183.186328 91.560008 -90)
    (descr "Capacitor SMD 0201")
    (tags "capacitor SMD 0201")
    (property "Author" "Antmicro")
    (property "Dielectric" "")
    (property "License" "Apache-2.0")
    (property "MPN" "CC0201KRX6S5BB104")
    (property "Manufacturer" "Yaego")
    (property "Sheetfile" "fpga-power.kicad_sch")
    (property "Sheetname" "FPGA power")
    (property "Val" "100n")
    (property "Voltage" "")
    (property "ki_description" " ")
    (attr smd)
    (fp_text reference "C66" (at -10.330008 -18.333672 90) (layer "B.SilkS")
        (effects (font (size 0.7 0.7) (thickness 0.15)) (justify left bottom mirror))
    )
    (fp_text value "C_100n_0201" (at 0 -1.4 90) (layer "B.Fab") hide
        (effects (font (size 0.7 0.7) (thickness 0.15)) (justify left bottom mirror))
    )
    (fp_text user "${REFERENCE}" (at -0.72 -3.4 90) (layer "B.Fab") hide
        (effects (font (size 0.7 0.7) (thickness 0.15)) (justify left bottom mirror))
    )
    (fp_text user "License: Apache-2.0" (at -0.72 -4.4 90) (layer "B.Fab") hide
        (effects (font (size 0.7 0.7) (thickness 0.15)) (justify left bottom mirror))
    )
    (fp_text user "Author: Antmicro" (at -0.72 -5.4 90) (layer "B.Fab") hide
        (effects (font (size 0.7 0.7) (thickness 0.15)) (justify left bottom mirror))
    )
    (fp_rect (start -0.72 0.38) (end 0.72 -0.38)
      (stroke (width 0.05) (type solid)) (fill none) (layer "B.CrtYd"))
    (fp_rect (start 0.3 -0.15) (end -0.301 0.149)
      (stroke (width 0.15) (type solid)) (fill none) (layer "B.Fab"))
    (pad "" smd roundrect (at -0.349 0.002 270) (size 0.318 0.36) (layers "B.Paste") (roundrect_rratio 0.25))
    (pad "" smd roundrect (at 0.341 0.002 270) (size 0.318 0.36) (layers "B.Paste") (roundrect_rratio 0.25))
    (pad "1" smd roundrect (at -0.321 0.002 270) (size 0.46 0.4) (layers "B.Cu" "B.Mask") (roundrect_rratio 0.25)
      (net 147 "1V0_SYS") (pintype "passive"))
    (pad "2" smd roundrect (at 0.32 0.002 270) (size 0.46 0.4) (layers "B.Cu" "B.Mask") (roundrect_rratio 0.25)
      (net 9 "GND") (pintype "passive"))
  )
	(footprint "data-center-rdimm-ddr4-tester-footprints:C_0201" (layer "B.Cu")
    (at 183.186328 93.560008 -90)
    (descr "Capacitor SMD 0201")
    (tags "capacitor SMD 0201")
    (property "Author" "Antmicro")
    (property "Dielectric" "")
    (property "License" "Apache-2.0")
    (property "MPN" "CC0201KRX6S5BB104")
    (property "Manufacturer" "Yaego")
    (property "Sheetfile" "fpga-power.kicad_sch")
    (property "Sheetname" "FPGA power")
    (property "Val" "100n")
    (property "Voltage" "")
    (property "ki_description" " ")
    (attr smd)
    (fp_text reference "C68" (at -10.340008 -18.383672 90) (layer "B.SilkS")
        (effects (font (size 0.7 0.7) (thickness 0.15)) (justify left bottom mirror))
    )
    (fp_text value "C_100n_0201" (at 0 -1.4 90) (layer "B.Fab") hide
        (effects (font (size 0.7 0.7) (thickness 0.15)) (justify left bottom mirror))
    )
    (fp_text user "License: Apache-2.0" (at -0.72 -4.4 90) (layer "B.Fab") hide
        (effects (font (size 0.7 0.7) (thickness 0.15)) (justify left bottom mirror))
    )
    (fp_text user "${REFERENCE}" (at -0.72 -3.4 90) (layer "B.Fab") hide
        (effects (font (size 0.7 0.7) (thickness 0.15)) (justify left bottom mirror))
    )
    (fp_text user "Author: Antmicro" (at -0.72 -5.4 90) (layer "B.Fab") hide
        (effects (font (size 0.7 0.7) (thickness 0.15)) (justify left bottom mirror))
    )
    (fp_rect (start -0.72 0.38) (end 0.72 -0.38)
      (stroke (width 0.05) (type solid)) (fill none) (layer "B.CrtYd"))
    (fp_rect (start 0.3 -0.15) (end -0.301 0.149)
      (stroke (width 0.15) (type solid)) (fill none) (layer "B.Fab"))
    (pad "" smd roundrect (at -0.349 0.002 270) (size 0.318 0.36) (layers "B.Paste") (roundrect_rratio 0.25))
    (pad "" smd roundrect (at 0.341 0.002 270) (size 0.318 0.36) (layers "B.Paste") (roundrect_rratio 0.25))
    (pad "1" smd roundrect (at -0.321 0.002 270) (size 0.46 0.4) (layers "B.Cu" "B.Mask") (roundrect_rratio 0.25)
      (net 147 "1V0_SYS") (pintype "passive"))
    (pad "2" smd roundrect (at 0.32 0.002 270) (size 0.46 0.4) (layers "B.Cu" "B.Mask") (roundrect_rratio 0.25)
      (net 9 "GND") (pintype "passive"))
  )
)
